#ISCELL
  mstr_misc dns *
  *
#ISCELL
  mstr_symbols cad_note *
  *
#ISCELL
  mstr_symbols design_note *
  *
#ISCELL
  mstr_symbols intel_corp_bpage *
  *
#ISCELL
  mstr_standard offpage *
  page139_i101
#ISCELL
  mstr_standard offpage *
  page139_i102
#ISCELL
  mstr_standard offpage *
  page139_i103
#ISCELL
  mstr_standard offpage *
  page139_i104
#ISCELL
  mstr_standard offpage *
  page139_i105
#ISCELL
  mstr_standard offpage *
  page139_i106
#ISCELL
  mstr_standard offpage *
  page139_i107
#ISCELL
  mstr_standard offpage *
  page139_i108
#CELL
  mstr_discrete crystal *
  page139_i109
#CELL
  mstr_discrete res *
  page139_i110
#CELL
  mstr_discrete cap *
  page139_i111
#CELL
  mstr_discrete cap *
  page139_i112
#ISCELL
  mstr_symbols gnd *
  page139_i113
#ISCELL
  mstr_symbols gnd *
  page139_i114
#ISCELL
  mstr_standard offpage *
  page139_i115
#ISCELL
  mstr_standard offpage *
  page139_i116
#ISCELL
  mstr_standard offpage *
  page139_i117
#ISCELL
  mstr_standard offpage *
  page139_i118
#ISCELL
  mstr_standard offpage *
  page139_i127
#CELL
  mstr_discrete res *
  page139_i128
#CELL
  mstr_discrete res *
  page139_i129
#CELL
  mstr_discrete res *
  page139_i130
#ISCELL
  mstr_standard offpage *
  page139_i131
#ISCELL
  mstr_standard offpage *
  page139_i132
#ISCELL
  mstr_standard offpage *
  page139_i133
#CELL
  mstr_discrete cap *
  page139_i134
#CELL
  mstr_discrete cap *
  page139_i135
#CELL
  mstr_discrete cap *
  page139_i136
#ISCELL
  mstr_symbols gnd *
  page139_i137
#ISCELL
  mstr_symbols gnd *
  page139_i138
#ISCELL
  mstr_symbols gnd *
  page139_i139
#CELL
  mstr_discrete cap *
  page139_i140
#CELL
  mstr_discrete cap *
  page139_i142
#CELL
  dev_discrete cap_a *
  page139_i143
#CELL
  dev_discrete cap_a *
  page139_i144
#CELL
  dev_discrete cap_a *
  page139_i145
#CELL
  dev_discrete cap_a *
  page139_i146
#ISCELL
  mstr_symbols gnd *
  page139_i147
#CELL
  dev_discrete cap_a *
  page139_i149
#CELL
  dev_discrete cap_a *
  page139_i150
#CELL
  dev_discrete cap_a *
  page139_i151
#CELL
  dev_discrete cap_a *
  page139_i152
#CELL
  mstr_discrete cap *
  page139_i153
#ISCELL
  mstr_symbols p1v5_lan *
  page139_i154
#CELL
  mstr_discrete cap *
  page139_i155
#ISCELL
  mstr_symbols gnd *
  page139_i156
#CELL
  dev_discrete cap_a *
  page139_i157
#CELL
  dev_discrete cap_a *
  page139_i158
#CELL
  dev_discrete cap_a *
  page139_i159
#CELL
  dev_discrete cap_a *
  page139_i160
#CELL
  mstr_discrete cap *
  page139_i161
#ISCELL
  mstr_symbols p0v9_lan *
  page139_i162
#CELL
  dev_discrete cap_a *
  page139_i163
#ISCELL
  mstr_symbols gnd *
  page139_i164
#ISCELL
  mstr_standard offpage *
  page139_i165
#ISCELL
  mstr_standard offpage *
  page139_i166
#ISCELL
  mstr_standard offpage *
  page139_i167
#ISCELL
  mstr_standard offpage *
  page139_i172
#CELL
  mstr_discrete res *
  page139_i173
#CELL
  mstr_discrete res *
  page139_i174
#ISCELL
  mstr_standard offpage *
  page139_i175
#ISCELL
  mstr_symbols gnd *
  page139_i176
#CELL
  mstr_discrete res *
  page139_i177
#CELL
  mstr_discrete res *
  page139_i178
#CELL
  mstr_discrete res *
  page139_i179
#ISCELL
  mstr_symbols p3v3_stby *
  page139_i180
#CELL
  mstr_discrete res *
  page139_i181
#ISCELL
  mstr_symbols p3v3_stby *
  page139_i182
#ISCELL
  mstr_standard offpage *
  page139_i183
#ISCELL
  mstr_standard offpage *
  page139_i184
#ISCELL
  mstr_standard offpage *
  page139_i185
#ISCELL
  mstr_symbols p3v3_stby *
  page139_i186
#ISCELL
  mstr_symbols p3v3_stby *
  page139_i188
#ISCELL
  mstr_symbols p3v3_stby *
  page139_i189
#ISCELL
  mstr_standard offpage *
  page139_i191
#ISCELL
  mstr_standard offpage *
  page139_i192
#CELL
  mstr_discrete res *
  page139_i193
#ISCELL
  mstr_symbols p3v3_stby *
  page139_i194
#CELL
  mstr_discrete res *
  page139_i195
#ISCELL
  mstr_standard offpage *
  page139_i197
#ISCELL
  mstr_standard offpage *
  page139_i198
#ISCELL
  mstr_symbols p3v3_stby *
  page139_i199
#CELL
  mstr_discrete res *
  page139_i200
#CELL
  mstr_discrete res *
  page139_i201
#ISCELL
  mstr_standard offpage *
  page139_i202
#ISCELL
  mstr_standard offpage *
  page139_i203
#ISCELL
  mstr_symbols gnd *
  page139_i204
#ISCELL
  mstr_standard offpage *
  page139_i206
#ISCELL
  mstr_symbols gnd *
  page139_i207
#ISCELL
  mstr_standard offpage *
  page139_i209
#ISCELL
  mstr_symbols gnd *
  page139_i211
#CELL
  mstr_discrete res *
  page139_i212
#CELL
  mstr_discrete res *
  page139_i213
#CELL
  mstr_discrete res *
  page139_i214
#ISCELL
  mstr_standard offpage *
  page139_i218
#ISCELL
  mstr_standard offpage *
  page139_i219
#ISCELL
  mstr_standard offpage *
  page139_i220
#ISCELL
  mstr_standard offpage *
  page139_i223
#ISCELL
  mstr_standard offpage *
  page139_i224
#CELL
  mstr_discrete res *
  page139_i225
#ISCELL
  mstr_standard offpage *
  page139_i226
#ISCELL
  mstr_standard offpage *
  page139_i227
#CELL
  mstr_discrete res *
  page139_i228
#CELL
  mstr_discrete res *
  page139_i229
#ISCELL
  mstr_standard offpage *
  page139_i230
#ISCELL
  mstr_standard offpage *
  page139_i231
#ISCELL
  mstr_standard offpage *
  page139_i233
#CELL
  mstr_discrete res *
  page139_i235
#ISCELL
  mstr_standard offpage *
  page139_i236
#CELL
  mstr_discrete res *
  page139_i237
#CELL
  mstr_discrete res *
  page139_i238
#CELL
  mstr_discrete res *
  page139_i239
#CELL
  mstr_discrete res *
  page139_i240
#CELL
  dev_discrete cap_a *
  page139_i241
#CELL
  mstr_intel springville *
  page139_i72
#ISCELL
  mstr_symbols p0v9_lan *
  page139_i73
#ISCELL
  mstr_symbols p1v5_lan *
  page139_i74
#CELL
  mstr_discrete cap *
  page139_i76
#ISCELL
  mstr_symbols gnd *
  page139_i77
#ISCELL
  mstr_standard offpage *
  page139_i84
#ISCELL
  mstr_standard offpage *
  page139_i85
#ISCELL
  mstr_standard offpage *
  page139_i86
#CELL
  dev_discrete cap_a *
  page139_i87
#CELL
  dev_discrete cap_a *
  page139_i88
#CELL
  dev_discrete cap_a *
  page139_i89
#CELL
  dev_discrete cap_a *
  page139_i90
#ISCELL
  mstr_standard offpage *
  page139_i91
#ISCELL
  mstr_standard offpage *
  page139_i92
#ISCELL
  mstr_standard offpage *
  page139_i93
#ISCELL
  mstr_standard offpage *
  page139_i94
